#ISCELL
  mstr_misc dns *
  *
#ISCELL
  mstr_symbols cad_note *
  *
#ISCELL
  mstr_symbols design_note *
  *
#ISCELL
  mstr_symbols intel_corp_bpage *
  *
#CELL
  mstr_discrete res *
  page239_i100
#CELL
  mstr_discrete res *
  page239_i101
#CELL
  w_hdl 21k5r2f-gp *
  page239_i102
#CELL
  mstr_discrete cap *
  page239_i104
#ISCELL
  mstr_symbols gnd *
  page239_i105
#CELL
  dev_discrete cap_a *
  page239_i111
#CELL
  mstr_discrete cap *
  page239_i12
#ISCELL
  mstr_symbols gnd *
  page239_i16
#CELL
  mstr_discrete cap *
  page239_i22
#CELL
  mstr_discrete cap *
  page239_i30
#ISCELL
  mstr_standard offpage *
  page239_i33
#ISCELL
  mstr_symbols p3v3_stby *
  page239_i35
#ISCELL
  mstr_symbols gnd *
  page239_i38
#ISCELL
  mstr_symbols gnd *
  page239_i39
#CELL
  mstr_discrete cap *
  page239_i4
#ISCELL
  mstr_standard offpage *
  page239_i42
#ISCELL
  mstr_symbols gnd *
  page239_i5
#CELL
  mstr_discrete res *
  page239_i6
#ISCELL
  mstr_symbols gnd *
  page239_i62
#ISCELL
  mstr_symbols p3v3_stby *
  page239_i67
#ISCELL
  mstr_symbols gnd *
  page239_i69
#CELL
  mstr_discrete cap *
  page239_i7
#CELL
  mstr_vreg rt9059 *
  page239_i70
#CELL
  dev_discrete cap_a *
  page239_i71
#CELL
  mstr_discrete res *
  page239_i72
#CELL
  mstr_vreg rt9059 *
  page239_i73
#ISCELL
  mstr_symbols gnd *
  page239_i74
#ISCELL
  mstr_symbols p3v3_stby *
  page239_i75
#ISCELL
  mstr_standard offpage *
  page239_i76
#CELL
  mstr_discrete res *
  page239_i77
#ISCELL
  mstr_symbols p3v3_stby *
  page239_i78
#CELL
  mstr_discrete res *
  page239_i79
#CELL
  mstr_discrete cap *
  page239_i81
#ISCELL
  mstr_symbols gnd *
  page239_i82
#CELL
  mstr_discrete cap *
  page239_i83
#CELL
  mstr_discrete cap *
  page239_i84
#ISCELL
  mstr_symbols gnd *
  page239_i85
#ISCELL
  mstr_symbols gnd *
  page239_i88
#ISCELL
  mstr_symbols gnd *
  page239_i89
#ISCELL
  mstr_symbols gnd *
  page239_i9
#CELL
  dev_discrete cap_a *
  page239_i90
#CELL
  mstr_discrete cap *
  page239_i91
#CELL
  mstr_discrete cap *
  page239_i92
#ISCELL
  mstr_symbols gnd *
  page239_i93
#ISCELL
  mstr_standard offpage *
  page239_i94
#ISCELL
  mstr_symbols gnd *
  page239_i95
#ISCELL
  w_power w_vcc_circle *
  page239_i96
#ISCELL
  w_power w_vcc_circle *
  page239_i97
#CELL
  w_hdl 5k1r2f-2-gp *
  page239_i98
